(kicad_pcb
	(version 20260206)
	(generator "pcbnew")
	(generator_version "10.0")
	(general
		(thickness 1.6)
		(legacy_teardrops no)
	)
	(paper "A4")
	(title_block
		(title "netronome-mezz — pcbd0082-001_rev01_jul9_a.brd")
		(comment 1 "Open CloudServer (Microsoft) / footprints 659-669 of 714")
	)
	(layers
		(0 "F.Cu" signal "TOP")
		(4 "In1.Cu" signal "02_GND")
		(6 "In2.Cu" signal "03_SIG")
		(8 "In3.Cu" signal "04_SIG")
		(10 "In4.Cu" signal "05_GND")
		(12 "In5.Cu" signal "06_PWR1")
		(14 "In6.Cu" signal "07_SIG")
		(16 "In7.Cu" signal "08_SIG")
		(18 "In8.Cu" signal "09_GND")
		(2 "B.Cu" signal "BOTTOM")
		(9 "F.Adhes" user "F.Adhesive")
		(11 "B.Adhes" user "B.Adhesive")
		(13 "F.Paste" user "Package Geometry/Pastemask Top")
		(15 "B.Paste" user "Package Geometry/Pastemask Bottom")
		(5 "F.SilkS" user "Ref Des/Silkscreen Top")
		(7 "B.SilkS" user "Ref Des/Silkscreen Bottom")
		(1 "F.Mask" user "Board Geometry/Soldermask Top")
		(3 "B.Mask" user "Board Geometry/Soldermask Bottom")
		(17 "Dwgs.User" user "User.Drawings")
		(19 "Cmts.User" user "User.Comments")
		(21 "Eco1.User" user "User.Eco1")
		(23 "Eco2.User" user "User.Eco2")
		(25 "Edge.Cuts" user "Board Geometry/Outline")
		(27 "Margin" user)
		(31 "F.CrtYd" user "Package Geometry/Place Bound Top")
		(29 "B.CrtYd" user "Package Geometry/Place Bound Bottom")
		(35 "F.Fab" user "Ref Des/Assembly Top")
		(33 "B.Fab" user "Ref Des/Assembly Bottom")
		(45 "User.4" user "COMPVAL_TYPE_BOTTOM")
	)
	(footprint ""
		(layer "B.Cu")
		(at 26.289 9.525 90)
		(property "Reference" "R43"
			(at 0.22733 3.556 0)
			(unlocked yes)
			(layer "B.SilkS")
			(effects
				(font
					(size 0.7874 0.5842)
					(thickness 0.127)
				)
				(justify left mirror)
			)
		)
		(property "Value" "4.75K"
			(at 0.148158 1.3462 0)
			(unlocked yes)
			(layer "B.Fab")
			(hide yes)
			(effects
				(font
					(size 1.27 0.9652)
					(thickness 0.000001)
				)
				(justify left mirror)
			)
		)
		(property "Device Type" "REST4024"
			(at 0.148158 1.3462 0)
			(unlocked yes)
			(layer "B.Fab")
			(hide yes)
			(effects
				(font
					(size 1.27 0.9652)
					(thickness 0.000001)
				)
				(justify left mirror)
			)
		)
		(duplicate_pad_numbers_are_jumpers no)
		(fp_poly
			(pts
				(xy -0.635 1.0668) (xy -0.635 -1.0668) (xy 0.635 -1.0668) (xy 0.635 1.0668)
			)
			(stroke
				(width 0)
				(type default)
			)
			(fill no)
			(layer "B.CrtYd")
		)
		(fp_line
			(start 0.254 -0.508)
			(end -0.254 -0.508)
			(stroke
				(width 0.0254)
				(type default)
			)
			(layer "B.Fab")
		)
		(fp_line
			(start -0.254 -0.508)
			(end -0.254 0.508)
			(stroke
				(width 0.0254)
				(type default)
			)
			(layer "B.Fab")
		)
		(fp_line
			(start 0.254 0.508)
			(end 0.254 -0.508)
			(stroke
				(width 0.0254)
				(type default)
			)
			(layer "B.Fab")
		)
		(fp_line
			(start -0.254 0.508)
			(end 0.254 0.508)
			(stroke
				(width 0.0254)
				(type default)
			)
			(layer "B.Fab")
		)
		(pad "1" smd rect
			(at 0 -0.4191 270)
			(size 0.508 0.5334)
			(layers "B.Cu" "B.Mask" "B.Paste")
			(net "VDD_3.3V")
		)
		(pad "2" smd rect
			(at 0 0.4191 270)
			(size 0.508 0.5334)
			(layers "B.Cu" "B.Mask" "B.Paste")
			(net "PGRM_JTAG_TDO")
		)
		(zone
			(layer "B.Cu")
			(hatch none 0.5)
			(connect_pads
				(clearance 0)
			)
			(min_thickness 0.25)
			(keepout
				(tracks not_allowed)
				(vias allowed)
				(pads allowed)
				(copperpour not_allowed)
				(footprints allowed)
			)
			(placement
				(enabled no)
				(sheetname "")
			)
			(fill
				(thermal_gap 0.5)
				(thermal_bridge_width 0.5)
				(island_removal_mode 0)
			)
			(polygon
				(pts
					(xy 26.2636 9.5504) (xy 26.3144 9.5504) (xy 26.3144 9.4996) (xy 26.2636 9.4996)
				)
			)
		)
	)
	(footprint ""
		(layer "B.Cu")
		(at 81.850992 7.498994)
		(property "Reference" "V1_A-BA1"
			(at 0 0 0)
			(layer "B.SilkS")
			(hide yes)
			(effects
				(font
					(size 1.27 1.27)
				)
				(justify mirror)
			)
		)
		(property "Value" ""
			(at 0 0 0)
			(layer "B.Fab")
			(effects
				(font
					(size 1.27 1.27)
				)
				(justify mirror)
			)
		)
		(duplicate_pad_numbers_are_jumpers no)
		(pad "1" thru_hole circle
			(at 0 0 180)
			(size 0.4572 0.4572)
			(drill 0.20574)
			(layers "*.Cu" "*.Mask")
			(remove_unused_layers no)
			(net "DDR0_32A_BA1")
			(clearance 0.1143)
			(thermal_gap 0.1143)
		)
	)
	(footprint ""
		(layer "B.Cu")
		(at 82.55 40.132 90)
		(property "Reference" "R331"
			(at 0.98933 0 0)
			(unlocked yes)
			(layer "B.SilkS")
			(effects
				(font
					(size 0.7874 0.5842)
					(thickness 0.127)
				)
				(justify left mirror)
			)
		)
		(property "Value" "0"
			(at 0.148158 1.7526 0)
			(unlocked yes)
			(layer "B.Fab")
			(hide yes)
			(effects
				(font
					(size 1.27 0.9652)
					(thickness 0.000001)
				)
				(justify left mirror)
			)
		)
		(property "Device Type" "REST1010"
			(at 0.148158 1.7526 0)
			(unlocked yes)
			(layer "B.Fab")
			(hide yes)
			(effects
				(font
					(size 1.27 0.9652)
					(thickness 0.000001)
				)
				(justify left mirror)
			)
		)
		(duplicate_pad_numbers_are_jumpers no)
		(fp_circle
			(center 0 0)
			(end 0 0.127)
			(stroke
				(width 0.2032)
				(type default)
			)
			(fill no)
			(layer "B.SilkS")
		)
		(fp_poly
			(pts
				(xy -0.7874 -1.6637) (xy 0.7874 -1.6637) (xy 0.7874 1.6637) (xy -0.7874 1.6637)
			)
			(stroke
				(width 0)
				(type default)
			)
			(fill no)
			(layer "B.CrtYd")
		)
		(fp_line
			(start 0.4064 -0.8128)
			(end -0.4064 -0.8128)
			(stroke
				(width 0.0254)
				(type default)
			)
			(layer "B.Fab")
		)
		(fp_line
			(start -0.4064 -0.8128)
			(end -0.4064 0.8128)
			(stroke
				(width 0.0254)
				(type default)
			)
			(layer "B.Fab")
		)
		(fp_line
			(start 0.4064 0.8128)
			(end 0.4064 -0.8128)
			(stroke
				(width 0.0254)
				(type default)
			)
			(layer "B.Fab")
		)
		(fp_line
			(start -0.4064 0.8128)
			(end 0.4064 0.8128)
			(stroke
				(width 0.0254)
				(type default)
			)
			(layer "B.Fab")
		)
		(pad "1" smd rect
			(at 0 -0.8001 270)
			(size 0.762 0.9652)
			(layers "B.Cu" "B.Mask" "B.Paste")
			(net "VDD_5.0V")
		)
		(pad "2" smd rect
			(at 0 0.8001 270)
			(size 0.762 0.9652)
			(layers "B.Cu" "B.Mask" "B.Paste")
			(net "11N2159")
		)
		(zone
			(layer "B.Cu")
			(hatch none 0.5)
			(connect_pads
				(clearance 0)
			)
			(min_thickness 0.25)
			(keepout
				(tracks not_allowed)
				(vias allowed)
				(pads allowed)
				(copperpour not_allowed)
				(footprints allowed)
			)
			(placement
				(enabled no)
				(sheetname "")
			)
			(fill
				(thermal_gap 0.5)
				(thermal_bridge_width 0.5)
				(island_removal_mode 0)
			)
			(polygon
				(pts
					(xy 82.296 40.0685) (xy 82.296 40.1955) (xy 82.804 40.1955) (xy 82.804 40.0685)
				)
			)
		)
	)
	(footprint ""
		(layer "B.Cu")
		(at 20.32 2.667 180)
		(property "Reference" "R399"
			(at 0.28067 1.016 270)
			(unlocked yes)
			(layer "B.SilkS")
			(effects
				(font
					(size 0.7874 0.5842)
					(thickness 0.127)
				)
				(justify left mirror)
			)
		)
		(property "Value" "4.75K"
			(at 0.148158 1.3462 90)
			(unlocked yes)
			(layer "B.Fab")
			(hide yes)
			(effects
				(font
					(size 1.27 0.9652)
					(thickness 0.000001)
				)
				(justify left mirror)
			)
		)
		(property "Device Type" "REST4024"
			(at 0.148158 1.3462 90)
			(unlocked yes)
			(layer "B.Fab")
			(hide yes)
			(effects
				(font
					(size 1.27 0.9652)
					(thickness 0.000001)
				)
				(justify left mirror)
			)
		)
		(duplicate_pad_numbers_are_jumpers no)
		(fp_poly
			(pts
				(xy -0.635 1.0668) (xy -0.635 -1.0668) (xy 0.635 -1.0668) (xy 0.635 1.0668)
			)
			(stroke
				(width 0)
				(type default)
			)
			(fill no)
			(layer "B.CrtYd")
		)
		(fp_line
			(start 0.254 0.508)
			(end 0.254 -0.508)
			(stroke
				(width 0.0254)
				(type default)
			)
			(layer "B.Fab")
		)
		(fp_line
			(start 0.254 -0.508)
			(end -0.254 -0.508)
			(stroke
				(width 0.0254)
				(type default)
			)
			(layer "B.Fab")
		)
		(fp_line
			(start -0.254 0.508)
			(end 0.254 0.508)
			(stroke
				(width 0.0254)
				(type default)
			)
			(layer "B.Fab")
		)
		(fp_line
			(start -0.254 -0.508)
			(end -0.254 0.508)
			(stroke
				(width 0.0254)
				(type default)
			)
			(layer "B.Fab")
		)
		(pad "1" smd rect
			(at 0 -0.4191)
			(size 0.508 0.5334)
			(layers "B.Cu" "B.Mask" "B.Paste")
			(net "EXT_3.3V")
		)
		(pad "2" smd rect
			(at 0 0.4191)
			(size 0.508 0.5334)
			(layers "B.Cu" "B.Mask" "B.Paste")
			(net "CPLD_SMBUS_SCL")
		)
		(zone
			(layer "B.Cu")
			(hatch none 0.5)
			(connect_pads
				(clearance 0)
			)
			(min_thickness 0.25)
			(keepout
				(tracks not_allowed)
				(vias allowed)
				(pads allowed)
				(copperpour not_allowed)
				(footprints allowed)
			)
			(placement
				(enabled no)
				(sheetname "")
			)
			(fill
				(thermal_gap 0.5)
				(thermal_bridge_width 0.5)
				(island_removal_mode 0)
			)
			(polygon
				(pts
					(xy 20.3454 2.6924) (xy 20.3454 2.6416) (xy 20.2946 2.6416) (xy 20.2946 2.6924)
				)
			)
		)
	)
	(footprint ""
		(layer "B.Cu")
		(at 78.650998 25.813004)
		(property "Reference" "V3_A-RAS"
			(at 0 0 0)
			(layer "B.SilkS")
			(hide yes)
			(effects
				(font
					(size 1.27 1.27)
				)
				(justify mirror)
			)
		)
		(property "Value" ""
			(at 0 0 0)
			(layer "B.Fab")
			(effects
				(font
					(size 1.27 1.27)
				)
				(justify mirror)
			)
		)
		(duplicate_pad_numbers_are_jumpers no)
		(pad "1" thru_hole circle
			(at 0 0 180)
			(size 0.4572 0.4572)
			(drill 0.20574)
			(layers "*.Cu" "*.Mask")
			(remove_unused_layers no)
			(net "DDR0_32A_RAS_L")
			(clearance 0.1143)
			(thermal_gap 0.1143)
		)
	)
	(footprint ""
		(layer "B.Cu")
		(at 44.73702 19.041999 -90)
		(property "Reference" "R321"
			(at 0 0 90)
			(layer "B.SilkS")
			(hide yes)
			(effects
				(font
					(size 1.27 1.27)
				)
				(justify mirror)
			)
		)
		(property "Value" ""
			(at 0 0 90)
			(layer "B.Fab")
			(effects
				(font
					(size 1.27 1.27)
				)
				(justify mirror)
			)
		)
		(duplicate_pad_numbers_are_jumpers no)
		(fp_circle
			(center 0 0)
			(end 0 -0.104648)
			(stroke
				(width 0.1016)
				(type default)
			)
			(fill no)
			(layer "B.SilkS")
		)
		(fp_poly
			(pts
				(xy 0.381 -0.889) (xy 0.381 0.889) (xy -0.381 0.889) (xy -0.381 -0.889)
			)
			(stroke
				(width 0)
				(type default)
			)
			(fill no)
			(layer "B.CrtYd")
		)
		(fp_line
			(start -0.508 1.016)
			(end 0.508 1.016)
			(stroke
				(width 0.0254)
				(type default)
			)
			(layer "B.Fab")
		)
		(fp_line
			(start 0.508 1.016)
			(end 0.508 -1.016)
			(stroke
				(width 0.0254)
				(type default)
			)
			(layer "B.Fab")
		)
		(fp_line
			(start -0.508 -1.016)
			(end -0.508 1.016)
			(stroke
				(width 0.0254)
				(type default)
			)
			(layer "B.Fab")
		)
		(fp_line
			(start 0.254 -1.016)
			(end -0.508 -1.016)
			(stroke
				(width 0.0254)
				(type default)
			)
			(layer "B.Fab")
		)
		(fp_line
			(start 0.508 -1.016)
			(end 0.254 -1.016)
			(stroke
				(width 0.0254)
				(type default)
			)
			(layer "B.Fab")
		)
		(pad "1" smd custom
			(at 0 -0.500126 90)
			(size 0.127 0.127)
			(layers "B.Cu" "B.Mask" "B.Paste")
			(net "GND")
			(options
				(clearance outline)
				(anchor circle)
			)
			(primitives
				(gr_poly
					(pts
						(xy -0.1778 0.254) (xy 0.1778 0.254) (xy 0.254 0.1778) (xy 0.254 -0.1778) (xy 0.1778 -0.254) (xy -0.1778 -0.254)
						(xy -0.254 -0.1778) (xy -0.254 0.1778)
					)
					(width 0)
					(fill yes)
				)
			)
		)
		(pad "2" smd custom
			(at 0 0.500126 90)
			(size 0.127 0.127)
			(layers "B.Cu" "B.Mask" "B.Paste")
			(net "NFP_CLK_REF_N")
			(options
				(clearance outline)
				(anchor circle)
			)
			(primitives
				(gr_poly
					(pts
						(xy -0.1778 0.254) (xy 0.1778 0.254) (xy 0.254 0.1778) (xy 0.254 -0.1778) (xy 0.1778 -0.254) (xy -0.1778 -0.254)
						(xy -0.254 -0.1778) (xy -0.254 0.1778)
					)
					(width 0)
					(fill yes)
				)
			)
		)
	)
	(footprint ""
		(layer "B.Cu")
		(at 48.26 0.762 180)
		(property "Reference" "C152"
			(at 0.145212 0.8763 270)
			(unlocked yes)
			(layer "B.SilkS")
			(effects
				(font
					(size 0.7874 0.5842)
					(thickness 0.127)
				)
				(justify left mirror)
			)
		)
		(property "Value" "0.22UF"
			(at 0.091846 0.2921 90)
			(unlocked yes)
			(layer "B.Fab")
			(hide yes)
			(effects
				(font
					(size 0.7874 0.5842)
					(thickness 0.2032)
				)
				(justify left mirror)
			)
		)
		(property "Device Type" "CAPC0062"
			(at 0.091846 0.2921 90)
			(unlocked yes)
			(layer "B.Fab")
			(hide yes)
			(effects
				(font
					(size 0.7874 0.5842)
					(thickness 0.2032)
				)
				(justify left mirror)
			)
		)
		(duplicate_pad_numbers_are_jumpers no)
		(fp_poly
			(pts
				(xy -0.635 1.0668) (xy -0.635 -1.0668) (xy 0.635 -1.0668) (xy 0.635 1.0668)
			)
			(stroke
				(width 0)
				(type default)
			)
			(fill no)
			(layer "B.CrtYd")
		)
		(fp_line
			(start 0.254 0.508)
			(end 0.254 -0.508)
			(stroke
				(width 0.0254)
				(type default)
			)
			(layer "B.Fab")
		)
		(fp_line
			(start 0.254 -0.508)
			(end -0.254 -0.508)
			(stroke
				(width 0.0254)
				(type default)
			)
			(layer "B.Fab")
		)
		(fp_line
			(start -0.254 0.508)
			(end 0.254 0.508)
			(stroke
				(width 0.0254)
				(type default)
			)
			(layer "B.Fab")
		)
		(fp_line
			(start -0.254 -0.508)
			(end -0.254 0.508)
			(stroke
				(width 0.0254)
				(type default)
			)
			(layer "B.Fab")
		)
		(pad "1" smd rect
			(at 0 -0.4191)
			(size 0.508 0.5334)
			(layers "B.Cu" "B.Mask" "B.Paste")
			(net "_NFP_PCIE0_PER7_N")
		)
		(pad "2" smd rect
			(at 0 0.4191)
			(size 0.508 0.5334)
			(layers "B.Cu" "B.Mask" "B.Paste")
			(net "NFP_PCIE0_PER7_N")
		)
		(zone
			(layer "B.Cu")
			(hatch none 0.5)
			(connect_pads
				(clearance 0)
			)
			(min_thickness 0.25)
			(keepout
				(tracks not_allowed)
				(vias allowed)
				(pads allowed)
				(copperpour not_allowed)
				(footprints allowed)
			)
			(placement
				(enabled no)
				(sheetname "")
			)
			(fill
				(thermal_gap 0.5)
				(thermal_bridge_width 0.5)
				(island_removal_mode 0)
			)
			(polygon
				(pts
					(xy 48.2854 0.7874) (xy 48.2854 0.7366) (xy 48.2346 0.7366) (xy 48.2346 0.7874)
				)
			)
		)
	)
	(footprint ""
		(layer "B.Cu")
		(at 83.450989 19.055994)
		(property "Reference" "V2_A-A06"
			(at 0 0 0)
			(layer "B.SilkS")
			(hide yes)
			(effects
				(font
					(size 1.27 1.27)
				)
				(justify mirror)
			)
		)
		(property "Value" ""
			(at 0 0 0)
			(layer "B.Fab")
			(effects
				(font
					(size 1.27 1.27)
				)
				(justify mirror)
			)
		)
		(duplicate_pad_numbers_are_jumpers no)
		(pad "1" thru_hole circle
			(at 0 0 180)
			(size 0.4572 0.4572)
			(drill 0.20574)
			(layers "*.Cu" "*.Mask")
			(remove_unused_layers no)
			(net "DDR0_32A_A6")
			(clearance 0.1143)
			(thermal_gap 0.1143)
		)
	)
	(footprint ""
		(layer "B.Cu")
		(at 45.737018 12.042013 90)
		(property "Reference" "R285"
			(at 0 0 90)
			(layer "B.SilkS")
			(hide yes)
			(effects
				(font
					(size 1.27 1.27)
				)
				(justify mirror)
			)
		)
		(property "Value" ""
			(at 0 0 90)
			(layer "B.Fab")
			(effects
				(font
					(size 1.27 1.27)
				)
				(justify mirror)
			)
		)
		(duplicate_pad_numbers_are_jumpers no)
		(fp_circle
			(center 0 0)
			(end 0 0.104648)
			(stroke
				(width 0.1016)
				(type default)
			)
			(fill no)
			(layer "B.SilkS")
		)
		(fp_poly
			(pts
				(xy 0.381 -0.889) (xy 0.381 0.889) (xy -0.381 0.889) (xy -0.381 -0.889)
			)
			(stroke
				(width 0)
				(type default)
			)
			(fill no)
			(layer "B.CrtYd")
		)
		(fp_line
			(start 0.508 -1.016)
			(end 0.254 -1.016)
			(stroke
				(width 0.0254)
				(type default)
			)
			(layer "B.Fab")
		)
		(fp_line
			(start 0.254 -1.016)
			(end -0.508 -1.016)
			(stroke
				(width 0.0254)
				(type default)
			)
			(layer "B.Fab")
		)
		(fp_line
			(start -0.508 -1.016)
			(end -0.508 1.016)
			(stroke
				(width 0.0254)
				(type default)
			)
			(layer "B.Fab")
		)
		(fp_line
			(start 0.508 1.016)
			(end 0.508 -1.016)
			(stroke
				(width 0.0254)
				(type default)
			)
			(layer "B.Fab")
		)
		(fp_line
			(start -0.508 1.016)
			(end 0.508 1.016)
			(stroke
				(width 0.0254)
				(type default)
			)
			(layer "B.Fab")
		)
		(pad "1" smd custom
			(at 0 -0.500126 270)
			(size 0.127 0.127)
			(layers "B.Cu" "B.Mask" "B.Paste")
			(net "GND")
			(options
				(clearance outline)
				(anchor circle)
			)
			(primitives
				(gr_poly
					(pts
						(xy -0.1778 0.254) (xy 0.1778 0.254) (xy 0.254 0.1778) (xy 0.254 -0.1778) (xy 0.1778 -0.254) (xy -0.1778 -0.254)
						(xy -0.254 -0.1778) (xy -0.254 0.1778)
					)
					(width 0)
					(fill yes)
				)
			)
		)
		(pad "2" smd custom
			(at 0 0.500126 270)
			(size 0.127 0.127)
			(layers "B.Cu" "B.Mask" "B.Paste")
			(net "NFP_VDD_CORE_SENSE_VSS")
			(options
				(clearance outline)
				(anchor circle)
			)
			(primitives
				(gr_poly
					(pts
						(xy -0.1778 0.254) (xy 0.1778 0.254) (xy 0.254 0.1778) (xy 0.254 -0.1778) (xy 0.1778 -0.254) (xy -0.1778 -0.254)
						(xy -0.254 -0.1778) (xy -0.254 0.1778)
					)
					(width 0)
					(fill yes)
				)
			)
		)
	)
	(footprint ""
		(layer "B.Cu")
		(at 73.05101 17.455998)
		(property "Reference" "V_A-DQS3-N"
			(at 0 0 0)
			(layer "B.SilkS")
			(hide yes)
			(effects
				(font
					(size 1.27 1.27)
				)
				(justify mirror)
			)
		)
		(property "Value" ""
			(at 0 0 0)
			(layer "B.Fab")
			(effects
				(font
					(size 1.27 1.27)
				)
				(justify mirror)
			)
		)
		(duplicate_pad_numbers_are_jumpers no)
		(pad "1" thru_hole circle
			(at 0 0 180)
			(size 0.4572 0.4572)
			(drill 0.20574)
			(layers "*.Cu" "*.Mask")
			(remove_unused_layers no)
			(net "DDR0_32A_DQS3_N")
			(clearance 0.1143)
			(thermal_gap 0.1143)
		)
	)
	(footprint ""
		(layer "B.Cu")
		(at 40.894 48.641)
		(property "Reference" "TP4"
			(at 3.302 0.53467 0)
			(unlocked yes)
			(layer "B.SilkS")
			(effects
				(font
					(size 0.7874 0.5842)
					(thickness 0.127)
				)
				(justify left mirror)
			)
		)
		(property "Value" "*"
			(at 0.4826 -0.14732 0)
			(unlocked yes)
			(layer "B.Fab")
			(hide yes)
			(effects
				(font
					(size 1.27 0.9652)
					(thickness 0.000001)
				)
				(justify left mirror)
			)
		)
		(property "Device Type" "TP_SMALL"
			(at 0.4826 -0.14732 0)
			(unlocked yes)
			(layer "B.Fab")
			(hide yes)
			(effects
				(font
					(size 1.27 0.9652)
					(thickness 0.000001)
				)
				(justify left mirror)
			)
		)
		(duplicate_pad_numbers_are_jumpers no)
		(fp_line
			(start -0.8636 -0.8636)
			(end 0.8636 -0.8636)
			(stroke
				(width 0.1524)
				(type default)
			)
			(layer "B.SilkS")
		)
		(fp_line
			(start -0.8636 0.8636)
			(end -0.8636 -0.8636)
			(stroke
				(width 0.1524)
				(type default)
			)
			(layer "B.SilkS")
		)
		(fp_line
			(start 0.8636 -0.8636)
			(end 0.8636 0.8636)
			(stroke
				(width 0.1524)
				(type default)
			)
			(layer "B.SilkS")
		)
		(fp_line
			(start 0.8636 0.8636)
			(end -0.8636 0.8636)
			(stroke
				(width 0.1524)
				(type default)
			)
			(layer "B.SilkS")
		)
		(fp_poly
			(pts
				(xy 0.635 -0.635) (xy 0.635 0.635) (xy -0.635 0.635) (xy -0.635 -0.635)
			)
			(stroke
				(width 0)
				(type default)
			)
			(fill no)
			(layer "B.CrtYd")
		)
		(pad "1" smd rect
			(at 0 0 180)
			(size 1.27 1.27)
			(layers "B.Cu" "B.Mask" "B.Paste")
			(net "CNTRL_SPI_CS")
		)
	)
)
